(kicad_pcb
	(version 20260206)
	(generator "pcbnew")
	(generator_version "10.0")
	(general
		(thickness 1.21888)
		(legacy_teardrops no)
	)
	(paper "A4")
	(title_block
		(title "timecard-v8 — TimeCard-DC-V8_EXP.PcbDoc")
		(comment 1 "Time Appliance Project (Time Card) / footprints 107-109 of 288")
	)
	(layers
		(0 "F.Cu" signal "TOP")
		(4 "In1.Cu" signal "SGND")
		(6 "In2.Cu" signal "IN1")
		(8 "In3.Cu" signal "IN2")
		(10 "In4.Cu" signal "SGND1")
		(2 "B.Cu" signal "BOTTOM")
		(9 "F.Adhes" user "F.Adhesive")
		(11 "B.Adhes" user "B.Adhesive")
		(13 "F.Paste" user "Top Paste")
		(15 "B.Paste" user "Bottom Paste")
		(5 "F.SilkS" user "Top Overlay")
		(7 "B.SilkS" user "Bottom Overlay")
		(1 "F.Mask" user "Top Solder")
		(3 "B.Mask" user "Bottom Solder")
		(17 "Dwgs.User" user "User.Drawings")
		(19 "Cmts.User" user "User.Comments")
		(21 "Eco1.User" user "User.Eco1")
		(23 "Eco2.User" user "User.Eco2")
		(25 "Edge.Cuts" user)
		(27 "Margin" user)
		(31 "F.CrtYd" user "Top Courtyard")
		(29 "B.CrtYd" user "Bottom Courtyard")
		(35 "F.Fab" user "Top Component Center")
		(33 "B.Fab" user "Bottom Component Center")
	)
	(footprint "Connectors:PCIE_4LANE_EDGE"
		(layer "F.Cu")
		(at 118.02597 154.3547)
		(property "Reference" "P2"
			(at -12.64987 -0.282755 0)
			(unlocked yes)
			(layer "F.SilkS")
			(hide yes)
			(effects
				(font
					(size 0.762 0.762)
					(thickness 0.2286)
				)
				(justify left bottom)
			)
		)
		(property "Value" "PCIex4"
			(at -5.44907 18.557875 0)
			(unlocked yes)
			(layer "F.SilkS")
			(hide yes)
			(effects
				(font
					(size 0.762 0.762)
					(thickness 0.2286)
				)
				(justify left bottom)
			)
		)
		(sheetname "PCIe_JTAG")
		(sheetfile "PCIe_JTAG.kicad_sch")
		(duplicate_pad_numbers_are_jumpers no)
		(pad "A1" smd rect
			(at -16.49984 2.2286)
			(size 0.7112 3.2004)
			(layers "B.Cu" "B.Mask" "B.Paste")
			(net "PRSNT")
		)
		(pad "A2" smd rect
			(at -15.49985 2.7239)
			(size 0.7112 4.191)
			(layers "B.Cu" "B.Mask" "B.Paste")
			(net "+12V_PCIE")
		)
		(pad "A3" smd rect
			(at -14.49985 2.7239)
			(size 0.7112 4.191)
			(layers "B.Cu" "B.Mask" "B.Paste")
			(net "+12V_PCIE")
		)
		(pad "A4" smd rect
			(at -13.49985 2.7239)
			(size 0.7112 4.191)
			(layers "B.Cu" "B.Mask" "B.Paste")
			(net "GND")
		)
		(pad "A5" smd rect
			(at -12.49985 2.7239)
			(size 0.7112 4.191)
			(layers "B.Cu" "B.Mask" "B.Paste")
		)
		(pad "A6" smd rect
			(at -11.49985 2.7239)
			(size 0.7112 4.191)
			(layers "B.Cu" "B.Mask" "B.Paste")
		)
		(pad "A7" smd rect
			(at -10.49986 2.7239)
			(size 0.7112 4.191)
			(layers "B.Cu" "B.Mask" "B.Paste")
		)
		(pad "A8" smd rect
			(at -9.49986 2.7239)
			(size 0.7112 4.191)
			(layers "B.Cu" "B.Mask" "B.Paste")
		)
		(pad "A9" smd rect
			(at -8.49986 2.7239)
			(size 0.7112 4.191)
			(layers "B.Cu" "B.Mask" "B.Paste")
			(net "+3.3V_PCIE")
		)
		(pad "A10" smd rect
			(at -7.49986 2.7239)
			(size 0.7112 4.191)
			(layers "B.Cu" "B.Mask" "B.Paste")
			(net "+3.3V_PCIE")
		)
		(pad "A11" smd rect
			(at -6.49986 2.7239)
			(size 0.7112 4.191)
			(layers "B.Cu" "B.Mask" "B.Paste")
			(net "PCIE_PERST")
		)
		(pad "A12" smd rect
			(at -3.49987 2.7239)
			(size 0.7112 4.191)
			(layers "B.Cu" "B.Mask" "B.Paste")
			(net "GND")
		)
		(pad "A13" smd rect
			(at -2.49987 2.7239)
			(size 0.7112 4.191)
			(layers "B.Cu" "B.Mask" "B.Paste")
			(net "NetC44_1")
		)
		(pad "A14" smd rect
			(at -1.49987 2.7239)
			(size 0.7112 4.191)
			(layers "B.Cu" "B.Mask" "B.Paste")
			(net "NetC45_1")
		)
		(pad "A15" smd rect
			(at -0.49988 2.7239)
			(size 0.7112 4.191)
			(layers "B.Cu" "B.Mask" "B.Paste")
			(net "GND")
		)
		(pad "A16" smd rect
			(at 0.50012 2.7239)
			(size 0.7112 4.191)
			(layers "B.Cu" "B.Mask" "B.Paste")
			(net "NetC46_1")
		)
		(pad "A17" smd rect
			(at 1.50012 2.7239)
			(size 0.7112 4.191)
			(layers "B.Cu" "B.Mask" "B.Paste")
			(net "NetC47_1")
		)
		(pad "A18" smd rect
			(at 2.50012 2.7239)
			(size 0.7112 4.191)
			(layers "B.Cu" "B.Mask" "B.Paste")
			(net "GND")
		)
		(pad "A19" smd rect
			(at 3.50012 2.7239)
			(size 0.7112 4.191)
			(layers "B.Cu" "B.Mask" "B.Paste")
		)
		(pad "A20" smd rect
			(at 4.50011 2.7239)
			(size 0.7112 4.191)
			(layers "B.Cu" "B.Mask" "B.Paste")
			(net "GND")
		)
		(pad "A21" smd rect
			(at 5.50011 2.7239)
			(size 0.7112 4.191)
			(layers "B.Cu" "B.Mask" "B.Paste")
			(net "NetC48_1")
		)
		(pad "A22" smd rect
			(at 6.50011 2.7239)
			(size 0.7112 4.191)
			(layers "B.Cu" "B.Mask" "B.Paste")
			(net "NetC49_1")
		)
		(pad "A23" smd rect
			(at 7.50011 2.7239)
			(size 0.7112 4.191)
			(layers "B.Cu" "B.Mask" "B.Paste")
			(net "GND")
		)
		(pad "A24" smd rect
			(at 8.50011 2.7239)
			(size 0.7112 4.191)
			(layers "B.Cu" "B.Mask" "B.Paste")
			(net "GND")
		)
		(pad "A25" smd rect
			(at 9.5001 2.7239)
			(size 0.7112 4.191)
			(layers "B.Cu" "B.Mask" "B.Paste")
			(net "NetC50_1")
		)
		(pad "A26" smd rect
			(at 10.5001 2.7239)
			(size 0.7112 4.191)
			(layers "B.Cu" "B.Mask" "B.Paste")
			(net "NetC51_1")
		)
		(pad "A27" smd rect
			(at 11.5001 2.7239)
			(size 0.7112 4.191)
			(layers "B.Cu" "B.Mask" "B.Paste")
			(net "GND")
		)
		(pad "A28" smd rect
			(at 12.5001 2.7239)
			(size 0.7112 4.191)
			(layers "B.Cu" "B.Mask" "B.Paste")
			(net "GND")
		)
		(pad "A29" smd rect
			(at 13.5001 2.7239)
			(size 0.7112 4.191)
			(layers "B.Cu" "B.Mask" "B.Paste")
			(net "NetC52_1")
		)
		(pad "A30" smd rect
			(at 14.50009 2.7239)
			(size 0.7112 4.191)
			(layers "B.Cu" "B.Mask" "B.Paste")
			(net "NetC53_1")
		)
		(pad "A31" smd rect
			(at 15.50009 2.7239)
			(size 0.7112 4.191)
			(layers "B.Cu" "B.Mask" "B.Paste")
			(net "GND")
		)
		(pad "A32" smd rect
			(at 16.50009 2.7239)
			(size 0.7112 4.191)
			(layers "B.Cu" "B.Mask" "B.Paste")
		)
		(pad "B1" smd rect
			(at -16.49984 2.7239)
			(size 0.7112 4.191)
			(layers "F.Cu" "F.Mask" "F.Paste")
			(net "+12V_PCIE")
		)
		(pad "B2" smd rect
			(at -15.49985 2.7239)
			(size 0.7112 4.191)
			(layers "F.Cu" "F.Mask" "F.Paste")
			(net "+12V_PCIE")
		)
		(pad "B3" smd rect
			(at -14.49985 2.7239)
			(size 0.7112 4.191)
			(layers "F.Cu" "F.Mask" "F.Paste")
			(net "+12V_PCIE")
		)
		(pad "B4" smd rect
			(at -13.49985 2.7239)
			(size 0.7112 4.191)
			(layers "F.Cu" "F.Mask" "F.Paste")
			(net "GND")
		)
		(pad "B5" smd rect
			(at -12.49985 2.7239)
			(size 0.7112 4.191)
			(layers "F.Cu" "F.Mask" "F.Paste")
		)
		(pad "B6" smd rect
			(at -11.49985 2.7239)
			(size 0.7112 4.191)
			(layers "F.Cu" "F.Mask" "F.Paste")
		)
		(pad "B7" smd rect
			(at -10.49986 2.7239)
			(size 0.7112 4.191)
			(layers "F.Cu" "F.Mask" "F.Paste")
			(net "GND")
		)
		(pad "B8" smd rect
			(at -9.49986 2.7239)
			(size 0.7112 4.191)
			(layers "F.Cu" "F.Mask" "F.Paste")
			(net "+3.3V_PCIE")
		)
		(pad "B9" smd rect
			(at -8.49986 2.7239)
			(size 0.7112 4.191)
			(layers "F.Cu" "F.Mask" "F.Paste")
		)
		(pad "B10" smd rect
			(at -7.49986 2.7239)
			(size 0.7112 4.191)
			(layers "F.Cu" "F.Mask" "F.Paste")
		)
		(pad "B11" smd rect
			(at -6.49986 2.7239)
			(size 0.7112 4.191)
			(layers "F.Cu" "F.Mask" "F.Paste")
		)
		(pad "B12" smd rect
			(at -3.49987 2.7239)
			(size 0.7112 4.191)
			(layers "F.Cu" "F.Mask" "F.Paste")
		)
		(pad "B13" smd rect
			(at -2.49987 2.7239)
			(size 0.7112 4.191)
			(layers "F.Cu" "F.Mask" "F.Paste")
			(net "GND")
		)
		(pad "B14" smd rect
			(at -1.49987 2.7239)
			(size 0.7112 4.191)
			(layers "F.Cu" "F.Mask" "F.Paste")
			(net "PCIE_RX0_P")
		)
		(pad "B15" smd rect
			(at -0.49988 2.7239)
			(size 0.7112 4.191)
			(layers "F.Cu" "F.Mask" "F.Paste")
			(net "PCIE_RX0_N")
		)
		(pad "B16" smd rect
			(at 0.50012 2.7239)
			(size 0.7112 4.191)
			(layers "F.Cu" "F.Mask" "F.Paste")
			(net "GND")
		)
		(pad "B17" smd rect
			(at 1.50012 2.7239)
			(size 0.7112 4.191)
			(layers "F.Cu" "F.Mask" "F.Paste")
			(net "NetP2_B17")
		)
		(pad "B18" smd rect
			(at 2.50012 2.7239)
			(size 0.7112 4.191)
			(layers "F.Cu" "F.Mask" "F.Paste")
			(net "GND")
		)
		(pad "B19" smd rect
			(at 3.50012 2.7239)
			(size 0.7112 4.191)
			(layers "F.Cu" "F.Mask" "F.Paste")
			(net "PCIE_RX1_P")
		)
		(pad "B20" smd rect
			(at 4.50011 2.7239)
			(size 0.7112 4.191)
			(layers "F.Cu" "F.Mask" "F.Paste")
			(net "PCIE_RX1_N")
		)
		(pad "B21" smd rect
			(at 5.50011 2.7239)
			(size 0.7112 4.191)
			(layers "F.Cu" "F.Mask" "F.Paste")
			(net "GND")
		)
		(pad "B22" smd rect
			(at 6.50011 2.7239)
			(size 0.7112 4.191)
			(layers "F.Cu" "F.Mask" "F.Paste")
			(net "GND")
		)
		(pad "B23" smd rect
			(at 7.50011 2.7239)
			(size 0.7112 4.191)
			(layers "F.Cu" "F.Mask" "F.Paste")
			(net "PCIE_RX2_P")
		)
		(pad "B24" smd rect
			(at 8.50011 2.7239)
			(size 0.7112 4.191)
			(layers "F.Cu" "F.Mask" "F.Paste")
			(net "PCIE_RX2_N")
		)
		(pad "B25" smd rect
			(at 9.5001 2.7239)
			(size 0.7112 4.191)
			(layers "F.Cu" "F.Mask" "F.Paste")
			(net "GND")
		)
		(pad "B26" smd rect
			(at 10.5001 2.7239)
			(size 0.7112 4.191)
			(layers "F.Cu" "F.Mask" "F.Paste")
			(net "GND")
		)
		(pad "B27" smd rect
			(at 11.5001 2.7239)
			(size 0.7112 4.191)
			(layers "F.Cu" "F.Mask" "F.Paste")
			(net "PCIE_RX3_P")
		)
		(pad "B28" smd rect
			(at 12.5001 2.7239)
			(size 0.7112 4.191)
			(layers "F.Cu" "F.Mask" "F.Paste")
			(net "PCIE_RX3_N")
		)
		(pad "B29" smd rect
			(at 13.5001 2.7239)
			(size 0.7112 4.191)
			(layers "F.Cu" "F.Mask" "F.Paste")
			(net "GND")
		)
		(pad "B30" smd rect
			(at 14.50009 2.7239)
			(size 0.7112 4.191)
			(layers "F.Cu" "F.Mask" "F.Paste")
		)
		(pad "B31" smd rect
			(at 15.50009 2.2286)
			(size 0.7112 3.2004)
			(layers "F.Cu" "F.Mask" "F.Paste")
			(net "NetP2_B31")
		)
		(pad "B32" smd rect
			(at 16.50009 2.7239)
			(size 0.7112 4.191)
			(layers "F.Cu" "F.Mask" "F.Paste")
			(net "GND")
		)
	)
	(footprint "Resistors:RESC1005X04N"
		(layer "F.Cu")
		(at 96.9261 142.2162)
		(property "Reference" "R23"
			(at 1.27491 0.808535 180)
			(unlocked yes)
			(layer "F.SilkS")
			(effects
				(font
					(size 0.762 0.762)
					(thickness 0.2286)
				)
				(justify left bottom)
			)
		)
		(property "Value" "ERJ-2GE0R00X"
			(at -0.2413 3.331845 0)
			(unlocked yes)
			(layer "F.SilkS")
			(hide yes)
			(effects
				(font
					(size 0.762 0.762)
					(thickness 0.2286)
				)
				(justify left bottom)
			)
		)
		(sheetname "PCIe_JTAG")
		(sheetfile "PCIe_JTAG.kicad_sch")
		(duplicate_pad_numbers_are_jumpers no)
		(pad "1" smd rect
			(at -0.425 0 90)
			(size 0.6 0.65)
			(layers "F.Cu" "F.Mask" "F.Paste")
			(net "PRSNT")
		)
		(pad "2" smd rect
			(at 0.425 0 90)
			(size 0.6 0.65)
			(layers "F.Cu" "F.Mask" "F.Paste")
			(net "NetP2_B17")
		)
	)
	(footprint "Vault:RESC1005X40X25NL05T05"
		(layer "F.Cu")
		(at 214.1261 80.0162 180)
		(property "Reference" "R92"
			(at -0.6286 -1.126921 0)
			(unlocked yes)
			(layer "F.SilkS")
			(effects
				(font
					(size 0.762 0.762)
					(thickness 0.2286)
				)
			)
		)
		(property "Value" "27_1%_0402"
			(at -2.732271 7.37632 90)
			(unlocked yes)
			(layer "F.SilkS")
			(hide yes)
			(effects
				(font
					(size 0.762 0.762)
					(thickness 0.2286)
				)
			)
		)
		(sheetname "USBUart_DipSelects")
		(sheetfile "USBUart_DipSelects.kicad_sch")
		(duplicate_pad_numbers_are_jumpers no)
		(pad "1" smd rect
			(at -0.45 0 270)
			(size 0.55 0.55)
			(layers "F.Cu" "F.Mask" "F.Paste")
			(net "FTDI_TX")
		)
		(pad "2" smd rect
			(at 0.45 0 270)
			(size 0.55 0.55)
			(layers "F.Cu" "F.Mask" "F.Paste")
			(net "NetR92_2")
		)
	)
)
